(kicad_pcb
	(version 20260206)
	(generator "pcbnew")
	(generator_version "10.0")
	(general
		(thickness 1.6)
		(legacy_teardrops no)
	)
	(paper "A4")
	(title_block
		(title "Wiwynn_Tioga_Pass_MB.brd")
		(comment 1 "Tioga Pass / footprint 4281 of 4770 (J9L2), pads 124-243 of 291")
	)
	(layers
		(0 "F.Cu" signal "TOP")
		(4 "In1.Cu" signal "L2GND")
		(6 "In2.Cu" signal "L3")
		(8 "In3.Cu" signal "L4GND")
		(10 "In4.Cu" signal "L5")
		(12 "In5.Cu" signal "L6GND")
		(14 "In6.Cu" signal "L7VCC")
		(16 "In7.Cu" signal "L8VCC")
		(18 "In8.Cu" signal "L9GND")
		(20 "In9.Cu" signal "L10")
		(22 "In10.Cu" signal "L11GND")
		(24 "In11.Cu" signal "L12")
		(26 "In12.Cu" signal "L13GND")
		(2 "B.Cu" signal "BOTTOM")
		(9 "F.Adhes" user "F.Adhesive")
		(11 "B.Adhes" user "B.Adhesive")
		(13 "F.Paste" user "Package Geometry/Pastemask Top")
		(15 "B.Paste" user "Package Geometry/Pastemask Bottom")
		(5 "F.SilkS" user "Ref Des/Silkscreen Top")
		(7 "B.SilkS" user "Ref Des/Silkscreen Bottom")
		(1 "F.Mask" user "Board Geometry/Soldermask Top")
		(3 "B.Mask" user "Board Geometry/Soldermask Bottom")
		(17 "Dwgs.User" user "User.Drawings")
		(19 "Cmts.User" user "User.Comments")
		(21 "Eco1.User" user "User.Eco1")
		(23 "Eco2.User" user "User.Eco2")
		(25 "Edge.Cuts" user "Board Geometry/Outline")
		(27 "Margin" user)
		(31 "F.CrtYd" user "Package Geometry/Place Bound Top")
		(29 "B.CrtYd" user "Package Geometry/Place Bound Bottom")
		(35 "F.Fab" user "Ref Des/Assembly Top")
		(33 "B.Fab" user "Ref Des/Assembly Bottom")
	)
	(footprint ""
		(layer "B.Cu")
		(at 29.699458 -142.477236 90)
		(property "Reference" "J9L2"
			(at 2.403348 38.118542 0)
			(unlocked yes)
			(layer "B.SilkS")
			(effects
				(font
					(size 0.7874 0.5842)
					(thickness 0.1524)
				)
				(justify left mirror)
			)
		)
		(property "Value" ""
			(at 0 0 90)
			(layer "B.Fab")
			(effects
				(font
					(size 1.27 1.27)
				)
				(justify mirror)
			)
		)
		(duplicate_pad_numbers_are_jumpers no)
		(pad "121" smd rect
			(at 0 107.100116 270)
			(size 1.8034 0.508)
			(layers "B.Cu" "B.Mask" "B.Paste")
			(net "M_L_DQS_DP<15>")
		)
		(pad "122" smd rect
			(at 0 107.95 270)
			(size 1.8034 0.508)
			(layers "B.Cu" "B.Mask" "B.Paste")
			(net "M_L_DQS_DN<15>")
		)
		(pad "123" smd rect
			(at 0 108.799884 270)
			(size 1.8034 0.508)
			(layers "B.Cu" "B.Mask" "B.Paste")
			(net "GND")
		)
		(pad "124" smd rect
			(at 0 109.650022 270)
			(size 1.8034 0.508)
			(layers "B.Cu" "B.Mask" "B.Paste")
			(net "M_L_DQ<54>")
		)
		(pad "125" smd rect
			(at 0 110.499906 270)
			(size 1.8034 0.508)
			(layers "B.Cu" "B.Mask" "B.Paste")
			(net "GND")
		)
		(pad "126" smd rect
			(at 0 111.350044 270)
			(size 1.8034 0.508)
			(layers "B.Cu" "B.Mask" "B.Paste")
			(net "M_L_DQ<50>")
		)
		(pad "127" smd rect
			(at 0 112.199928 270)
			(size 1.8034 0.508)
			(layers "B.Cu" "B.Mask" "B.Paste")
			(net "GND")
		)
		(pad "128" smd rect
			(at 0 113.050066 270)
			(size 1.8034 0.508)
			(layers "B.Cu" "B.Mask" "B.Paste")
			(net "M_L_DQ<60>")
		)
		(pad "129" smd rect
			(at 0 113.89995 270)
			(size 1.8034 0.508)
			(layers "B.Cu" "B.Mask" "B.Paste")
			(net "GND")
		)
		(pad "130" smd rect
			(at 0 114.750088 270)
			(size 1.8034 0.508)
			(layers "B.Cu" "B.Mask" "B.Paste")
			(net "M_L_DQ<56>")
		)
		(pad "131" smd rect
			(at 0 115.599972 270)
			(size 1.8034 0.508)
			(layers "B.Cu" "B.Mask" "B.Paste")
			(net "GND")
		)
		(pad "132" smd rect
			(at 0 116.45011 270)
			(size 1.8034 0.508)
			(layers "B.Cu" "B.Mask" "B.Paste")
			(net "M_L_DQS_DP<16>")
		)
		(pad "133" smd rect
			(at 0 117.299994 270)
			(size 1.8034 0.508)
			(layers "B.Cu" "B.Mask" "B.Paste")
			(net "M_L_DQS_DN<16>")
		)
		(pad "134" smd rect
			(at 0 118.149878 270)
			(size 1.8034 0.508)
			(layers "B.Cu" "B.Mask" "B.Paste")
			(net "GND")
		)
		(pad "135" smd rect
			(at 0 119.000016 270)
			(size 1.8034 0.508)
			(layers "B.Cu" "B.Mask" "B.Paste")
			(net "M_L_DQ<62>")
		)
		(pad "136" smd rect
			(at 0 119.8499 270)
			(size 1.8034 0.508)
			(layers "B.Cu" "B.Mask" "B.Paste")
			(net "GND")
		)
		(pad "137" smd rect
			(at 0 120.700038 270)
			(size 1.8034 0.508)
			(layers "B.Cu" "B.Mask" "B.Paste")
			(net "M_L_DQ<58>")
		)
		(pad "138" smd rect
			(at 0 121.549922 270)
			(size 1.8034 0.508)
			(layers "B.Cu" "B.Mask" "B.Paste")
			(net "GND")
		)
		(pad "139" smd rect
			(at 0 122.40006 270)
			(size 1.8034 0.508)
			(layers "B.Cu" "B.Mask" "B.Paste")
			(net "PVPP_KLM")
		)
		(pad "140" smd rect
			(at 0 123.249944 270)
			(size 1.8034 0.508)
			(layers "B.Cu" "B.Mask" "B.Paste")
			(net "PVPP_KLM")
		)
		(pad "141" smd rect
			(at 0 124.100082 270)
			(size 1.8034 0.508)
			(layers "B.Cu" "B.Mask" "B.Paste")
			(net "SMB_DDR_KLM_VPP_SCL")
		)
		(pad "142" smd rect
			(at 0 124.949966 270)
			(size 1.8034 0.508)
			(layers "B.Cu" "B.Mask" "B.Paste")
			(net "PVPP_KLM")
		)
		(pad "143" smd rect
			(at 0 125.800104 270)
			(size 1.8034 0.508)
			(layers "B.Cu" "B.Mask" "B.Paste")
			(net "PVPP_KLM")
		)
		(pad "144" smd rect
			(at 0 126.649988 270)
			(size 1.8034 0.508)
			(layers "B.Cu" "B.Mask" "B.Paste")
			(net "TP_CH_L_DIMM0_RFU_2")
		)
		(pad "145" smd rect
			(at -4.59994 0 270)
			(size 1.8034 0.508)
			(layers "B.Cu" "B.Mask" "B.Paste")
			(net "P12V_NVDIMM_KLM")
		)
		(pad "146" smd rect
			(at -4.59994 0.849884 270)
			(size 1.8034 0.508)
			(layers "B.Cu" "B.Mask" "B.Paste")
			(net "M_L_VREF")
		)
		(pad "147" smd rect
			(at -4.59994 1.700022 270)
			(size 1.8034 0.508)
			(layers "B.Cu" "B.Mask" "B.Paste")
			(net "GND")
		)
		(pad "148" smd rect
			(at -4.59994 2.549906 270)
			(size 1.8034 0.508)
			(layers "B.Cu" "B.Mask" "B.Paste")
			(net "M_L_DQ<5>")
		)
		(pad "149" smd rect
			(at -4.59994 3.400044 270)
			(size 1.8034 0.508)
			(layers "B.Cu" "B.Mask" "B.Paste")
			(net "GND")
		)
		(pad "150" smd rect
			(at -4.59994 4.249928 270)
			(size 1.8034 0.508)
			(layers "B.Cu" "B.Mask" "B.Paste")
			(net "M_L_DQ<1>")
		)
		(pad "151" smd rect
			(at -4.59994 5.100066 270)
			(size 1.8034 0.508)
			(layers "B.Cu" "B.Mask" "B.Paste")
			(net "GND")
		)
		(pad "152" smd rect
			(at -4.59994 5.94995 270)
			(size 1.8034 0.508)
			(layers "B.Cu" "B.Mask" "B.Paste")
			(net "M_L_DQS_DN<0>")
		)
		(pad "153" smd rect
			(at -4.59994 6.800088 270)
			(size 1.8034 0.508)
			(layers "B.Cu" "B.Mask" "B.Paste")
			(net "M_L_DQS_DP<0>")
		)
		(pad "154" smd rect
			(at -4.59994 7.649972 270)
			(size 1.8034 0.508)
			(layers "B.Cu" "B.Mask" "B.Paste")
			(net "GND")
		)
		(pad "155" smd rect
			(at -4.59994 8.50011 270)
			(size 1.8034 0.508)
			(layers "B.Cu" "B.Mask" "B.Paste")
			(net "M_L_DQ<7>")
		)
		(pad "156" smd rect
			(at -4.59994 9.349994 270)
			(size 1.8034 0.508)
			(layers "B.Cu" "B.Mask" "B.Paste")
			(net "GND")
		)
		(pad "157" smd rect
			(at -4.59994 10.199878 270)
			(size 1.8034 0.508)
			(layers "B.Cu" "B.Mask" "B.Paste")
			(net "M_L_DQ<3>")
		)
		(pad "158" smd rect
			(at -4.59994 11.050016 270)
			(size 1.8034 0.508)
			(layers "B.Cu" "B.Mask" "B.Paste")
			(net "GND")
		)
		(pad "159" smd rect
			(at -4.59994 11.8999 270)
			(size 1.8034 0.508)
			(layers "B.Cu" "B.Mask" "B.Paste")
			(net "M_L_DQ<13>")
		)
		(pad "160" smd rect
			(at -4.59994 12.750038 270)
			(size 1.8034 0.508)
			(layers "B.Cu" "B.Mask" "B.Paste")
			(net "GND")
		)
		(pad "161" smd rect
			(at -4.59994 13.599922 270)
			(size 1.8034 0.508)
			(layers "B.Cu" "B.Mask" "B.Paste")
			(net "M_L_DQ<9>")
		)
		(pad "162" smd rect
			(at -4.59994 14.45006 270)
			(size 1.8034 0.508)
			(layers "B.Cu" "B.Mask" "B.Paste")
			(net "GND")
		)
		(pad "163" smd rect
			(at -4.59994 15.299944 270)
			(size 1.8034 0.508)
			(layers "B.Cu" "B.Mask" "B.Paste")
			(net "M_L_DQS_DN<1>")
		)
		(pad "164" smd rect
			(at -4.59994 16.150082 270)
			(size 1.8034 0.508)
			(layers "B.Cu" "B.Mask" "B.Paste")
			(net "M_L_DQS_DP<1>")
		)
		(pad "165" smd rect
			(at -4.59994 16.999966 270)
			(size 1.8034 0.508)
			(layers "B.Cu" "B.Mask" "B.Paste")
			(net "GND")
		)
		(pad "166" smd rect
			(at -4.59994 17.850104 270)
			(size 1.8034 0.508)
			(layers "B.Cu" "B.Mask" "B.Paste")
			(net "M_L_DQ<15>")
		)
		(pad "167" smd rect
			(at -4.59994 18.699988 270)
			(size 1.8034 0.508)
			(layers "B.Cu" "B.Mask" "B.Paste")
			(net "GND")
		)
		(pad "168" smd rect
			(at -4.59994 19.550126 270)
			(size 1.8034 0.508)
			(layers "B.Cu" "B.Mask" "B.Paste")
			(net "M_L_DQ<11>")
		)
		(pad "169" smd rect
			(at -4.59994 20.40001 270)
			(size 1.8034 0.508)
			(layers "B.Cu" "B.Mask" "B.Paste")
			(net "GND")
		)
		(pad "170" smd rect
			(at -4.59994 21.249894 270)
			(size 1.8034 0.508)
			(layers "B.Cu" "B.Mask" "B.Paste")
			(net "M_L_DQ<21>")
		)
		(pad "171" smd rect
			(at -4.59994 22.100032 270)
			(size 1.8034 0.508)
			(layers "B.Cu" "B.Mask" "B.Paste")
			(net "GND")
		)
		(pad "172" smd rect
			(at -4.59994 22.949916 270)
			(size 1.8034 0.508)
			(layers "B.Cu" "B.Mask" "B.Paste")
			(net "M_L_DQ<17>")
		)
		(pad "173" smd rect
			(at -4.59994 23.800054 270)
			(size 1.8034 0.508)
			(layers "B.Cu" "B.Mask" "B.Paste")
			(net "GND")
		)
		(pad "174" smd rect
			(at -4.59994 24.649938 270)
			(size 1.8034 0.508)
			(layers "B.Cu" "B.Mask" "B.Paste")
			(net "M_L_DQS_DN<2>")
		)
		(pad "175" smd rect
			(at -4.59994 25.500076 270)
			(size 1.8034 0.508)
			(layers "B.Cu" "B.Mask" "B.Paste")
			(net "M_L_DQS_DP<2>")
		)
		(pad "176" smd rect
			(at -4.59994 26.34996 270)
			(size 1.8034 0.508)
			(layers "B.Cu" "B.Mask" "B.Paste")
			(net "GND")
		)
		(pad "177" smd rect
			(at -4.59994 27.200098 270)
			(size 1.8034 0.508)
			(layers "B.Cu" "B.Mask" "B.Paste")
			(net "M_L_DQ<23>")
		)
		(pad "178" smd rect
			(at -4.59994 28.049982 270)
			(size 1.8034 0.508)
			(layers "B.Cu" "B.Mask" "B.Paste")
			(net "GND")
		)
		(pad "179" smd rect
			(at -4.59994 28.90012 270)
			(size 1.8034 0.508)
			(layers "B.Cu" "B.Mask" "B.Paste")
			(net "M_L_DQ<19>")
		)
		(pad "180" smd rect
			(at -4.59994 29.750004 270)
			(size 1.8034 0.508)
			(layers "B.Cu" "B.Mask" "B.Paste")
			(net "GND")
		)
		(pad "181" smd rect
			(at -4.59994 30.599888 270)
			(size 1.8034 0.508)
			(layers "B.Cu" "B.Mask" "B.Paste")
			(net "M_L_DQ<29>")
		)
		(pad "182" smd rect
			(at -4.59994 31.450026 270)
			(size 1.8034 0.508)
			(layers "B.Cu" "B.Mask" "B.Paste")
			(net "GND")
		)
		(pad "183" smd rect
			(at -4.59994 32.29991 270)
			(size 1.8034 0.508)
			(layers "B.Cu" "B.Mask" "B.Paste")
			(net "M_L_DQ<25>")
		)
		(pad "184" smd rect
			(at -4.59994 33.150048 270)
			(size 1.8034 0.508)
			(layers "B.Cu" "B.Mask" "B.Paste")
			(net "GND")
		)
		(pad "185" smd rect
			(at -4.59994 33.999932 270)
			(size 1.8034 0.508)
			(layers "B.Cu" "B.Mask" "B.Paste")
			(net "M_L_DQS_DN<3>")
		)
		(pad "186" smd rect
			(at -4.59994 34.85007 270)
			(size 1.8034 0.508)
			(layers "B.Cu" "B.Mask" "B.Paste")
			(net "M_L_DQS_DP<3>")
		)
		(pad "187" smd rect
			(at -4.59994 35.699954 270)
			(size 1.8034 0.508)
			(layers "B.Cu" "B.Mask" "B.Paste")
			(net "GND")
		)
		(pad "188" smd rect
			(at -4.59994 36.550092 270)
			(size 1.8034 0.508)
			(layers "B.Cu" "B.Mask" "B.Paste")
			(net "M_L_DQ<31>")
		)
		(pad "189" smd rect
			(at -4.59994 37.399976 270)
			(size 1.8034 0.508)
			(layers "B.Cu" "B.Mask" "B.Paste")
			(net "GND")
		)
		(pad "190" smd rect
			(at -4.59994 38.250114 270)
			(size 1.8034 0.508)
			(layers "B.Cu" "B.Mask" "B.Paste")
			(net "M_L_DQ<27>")
		)
		(pad "191" smd rect
			(at -4.59994 39.099998 270)
			(size 1.8034 0.508)
			(layers "B.Cu" "B.Mask" "B.Paste")
			(net "GND")
		)
		(pad "192" smd rect
			(at -4.59994 39.949882 270)
			(size 1.8034 0.508)
			(layers "B.Cu" "B.Mask" "B.Paste")
			(net "M_L_ECC<5>")
		)
		(pad "193" smd rect
			(at -4.59994 40.80002 270)
			(size 1.8034 0.508)
			(layers "B.Cu" "B.Mask" "B.Paste")
			(net "GND")
		)
		(pad "194" smd rect
			(at -4.59994 41.649904 270)
			(size 1.8034 0.508)
			(layers "B.Cu" "B.Mask" "B.Paste")
			(net "M_L_ECC<1>")
		)
		(pad "195" smd rect
			(at -4.59994 42.500042 270)
			(size 1.8034 0.508)
			(layers "B.Cu" "B.Mask" "B.Paste")
			(net "GND")
		)
		(pad "196" smd rect
			(at -4.59994 43.349926 270)
			(size 1.8034 0.508)
			(layers "B.Cu" "B.Mask" "B.Paste")
			(net "M_L_DQS_DN<8>")
		)
		(pad "197" smd rect
			(at -4.59994 44.200064 270)
			(size 1.8034 0.508)
			(layers "B.Cu" "B.Mask" "B.Paste")
			(net "M_L_DQS_DP<8>")
		)
		(pad "198" smd rect
			(at -4.59994 45.049948 270)
			(size 1.8034 0.508)
			(layers "B.Cu" "B.Mask" "B.Paste")
			(net "GND")
		)
		(pad "199" smd rect
			(at -4.59994 45.900086 270)
			(size 1.8034 0.508)
			(layers "B.Cu" "B.Mask" "B.Paste")
			(net "M_L_ECC<7>")
		)
		(pad "200" smd rect
			(at -4.59994 46.74997 270)
			(size 1.8034 0.508)
			(layers "B.Cu" "B.Mask" "B.Paste")
			(net "GND")
		)
		(pad "201" smd rect
			(at -4.59994 47.600108 270)
			(size 1.8034 0.508)
			(layers "B.Cu" "B.Mask" "B.Paste")
			(net "M_L_ECC<3>")
		)
		(pad "202" smd rect
			(at -4.59994 48.449992 270)
			(size 1.8034 0.508)
			(layers "B.Cu" "B.Mask" "B.Paste")
			(net "GND")
		)
		(pad "203" smd rect
			(at -4.59994 49.299876 270)
			(size 1.8034 0.508)
			(layers "B.Cu" "B.Mask" "B.Paste")
			(net "M_L_CKE<3>")
		)
		(pad "204" smd rect
			(at -4.59994 50.150014 270)
			(size 1.8034 0.508)
			(layers "B.Cu" "B.Mask" "B.Paste")
			(net "PVDDQ_KLM")
		)
		(pad "205" smd rect
			(at -4.59994 50.999898 270)
			(size 1.8034 0.508)
			(layers "B.Cu" "B.Mask" "B.Paste")
			(net "TP_CH_L_DIMM0_RFU_0")
		)
		(pad "206" smd rect
			(at -4.59994 51.850036 270)
			(size 1.8034 0.508)
			(layers "B.Cu" "B.Mask" "B.Paste")
			(net "PVDDQ_KLM")
		)
		(pad "207" smd rect
			(at -4.59994 52.69992 270)
			(size 1.8034 0.508)
			(layers "B.Cu" "B.Mask" "B.Paste")
			(net "M_L_BG<1>")
		)
		(pad "208" smd rect
			(at -4.59994 53.550058 270)
			(size 1.8034 0.508)
			(layers "B.Cu" "B.Mask" "B.Paste")
			(net "M_L_ALERT_N")
		)
		(pad "209" smd rect
			(at -4.59994 54.399942 270)
			(size 1.8034 0.508)
			(layers "B.Cu" "B.Mask" "B.Paste")
			(net "PVDDQ_KLM")
		)
		(pad "210" smd rect
			(at -4.59994 55.25008 270)
			(size 1.8034 0.508)
			(layers "B.Cu" "B.Mask" "B.Paste")
			(net "M_L_MA<11>")
		)
		(pad "211" smd rect
			(at -4.59994 56.099964 270)
			(size 1.8034 0.508)
			(layers "B.Cu" "B.Mask" "B.Paste")
			(net "M_L_MA<7>")
		)
		(pad "212" smd rect
			(at -4.59994 56.950102 270)
			(size 1.8034 0.508)
			(layers "B.Cu" "B.Mask" "B.Paste")
			(net "PVDDQ_KLM")
		)
		(pad "213" smd rect
			(at -4.59994 57.799986 270)
			(size 1.8034 0.508)
			(layers "B.Cu" "B.Mask" "B.Paste")
			(net "M_L_MA<5>")
		)
		(pad "214" smd rect
			(at -4.59994 58.650124 270)
			(size 1.8034 0.508)
			(layers "B.Cu" "B.Mask" "B.Paste")
			(net "M_L_MA<4>")
		)
		(pad "215" smd rect
			(at -4.59994 59.500008 270)
			(size 1.8034 0.508)
			(layers "B.Cu" "B.Mask" "B.Paste")
			(net "PVDDQ_KLM")
		)
		(pad "216" smd rect
			(at -4.59994 60.349892 270)
			(size 1.8034 0.508)
			(layers "B.Cu" "B.Mask" "B.Paste")
			(net "M_L_MA<2>")
		)
		(pad "217" smd rect
			(at -4.59994 61.20003 270)
			(size 1.8034 0.508)
			(layers "B.Cu" "B.Mask" "B.Paste")
			(net "PVDDQ_KLM")
		)
		(pad "218" smd rect
			(at -4.59994 62.049914 270)
			(size 1.8034 0.508)
			(layers "B.Cu" "B.Mask" "B.Paste")
			(net "M_L_CLK_DP<3>")
		)
		(pad "219" smd rect
			(at -4.59994 62.900052 270)
			(size 1.8034 0.508)
			(layers "B.Cu" "B.Mask" "B.Paste")
			(net "M_L_CLK_DN<3>")
		)
		(pad "220" smd rect
			(at -4.59994 63.749936 270)
			(size 1.8034 0.508)
			(layers "B.Cu" "B.Mask" "B.Paste")
			(net "PVDDQ_KLM")
		)
		(pad "221" smd rect
			(at -4.59994 64.600074 270)
			(size 1.8034 0.508)
			(layers "B.Cu" "B.Mask" "B.Paste")
			(net "PVTT_KLM")
		)
		(pad "222" smd rect
			(at -4.59994 70.550024 270)
			(size 1.8034 0.508)
			(layers "B.Cu" "B.Mask" "B.Paste")
			(net "M_L_PAR")
		)
		(pad "223" smd rect
			(at -4.59994 71.399908 270)
			(size 1.8034 0.508)
			(layers "B.Cu" "B.Mask" "B.Paste")
			(net "PVDDQ_KLM")
		)
		(pad "224" smd rect
			(at -4.59994 72.250046 270)
			(size 1.8034 0.508)
			(layers "B.Cu" "B.Mask" "B.Paste")
			(net "M_L_BA<1>")
		)
		(pad "225" smd rect
			(at -4.59994 73.09993 270)
			(size 1.8034 0.508)
			(layers "B.Cu" "B.Mask" "B.Paste")
			(net "M_L_MA<10>")
		)
		(pad "226" smd rect
			(at -4.59994 73.950068 270)
			(size 1.8034 0.508)
			(layers "B.Cu" "B.Mask" "B.Paste")
			(net "PVDDQ_KLM")
		)
		(pad "227" smd rect
			(at -4.59994 74.799952 270)
			(size 1.8034 0.508)
			(layers "B.Cu" "B.Mask" "B.Paste")
			(net "TP_CH_L_DIMM0_RFU_1")
		)
		(pad "228" smd rect
			(at -4.59994 75.65009 270)
			(size 1.8034 0.508)
			(layers "B.Cu" "B.Mask" "B.Paste")
			(net "M_L_MA<14>")
		)
		(pad "229" smd rect
			(at -4.59994 76.499974 270)
			(size 1.8034 0.508)
			(layers "B.Cu" "B.Mask" "B.Paste")
			(net "PVDDQ_KLM")
		)
		(pad "230" smd rect
			(at -4.59994 77.350112 270)
			(size 1.8034 0.508)
			(layers "B.Cu" "B.Mask" "B.Paste")
			(net "FM_ADR_COMPLETE_KLM_N")
		)
		(pad "231" smd rect
			(at -4.59994 78.199996 270)
			(size 1.8034 0.508)
			(layers "B.Cu" "B.Mask" "B.Paste")
			(net "PVDDQ_KLM")
		)
		(pad "232" smd rect
			(at -4.59994 79.04988 270)
			(size 1.8034 0.508)
			(layers "B.Cu" "B.Mask" "B.Paste")
			(net "M_L_MA<13>")
		)
		(pad "233" smd rect
			(at -4.59994 79.900018 270)
			(size 1.8034 0.508)
			(layers "B.Cu" "B.Mask" "B.Paste")
			(net "PVDDQ_KLM")
		)
		(pad "234" smd rect
			(at -4.59994 80.749902 270)
			(size 1.8034 0.508)
			(layers "B.Cu" "B.Mask" "B.Paste")
			(net "M_L_MA<17>")
		)
		(pad "235" smd rect
			(at -4.59994 81.60004 270)
			(size 1.8034 0.508)
			(layers "B.Cu" "B.Mask" "B.Paste")
			(net "M_L_C<2>")
		)
		(pad "236" smd rect
			(at -4.59994 82.449924 270)
			(size 1.8034 0.508)
			(layers "B.Cu" "B.Mask" "B.Paste")
			(net "PVDDQ_KLM")
		)
		(pad "237" smd rect
			(at -4.59994 83.300062 270)
			(size 1.8034 0.508)
			(layers "B.Cu" "B.Mask" "B.Paste")
			(net "M_L_CS_N<7>")
		)
		(pad "238" smd rect
			(at -4.59994 84.149946 270)
			(size 1.8034 0.508)
			(layers "B.Cu" "B.Mask" "B.Paste")
			(net "GND")
		)
		(pad "239" smd rect
			(at -4.59994 85.000084 270)
			(size 1.8034 0.508)
			(layers "B.Cu" "B.Mask" "B.Paste")
			(net "GND")
		)
		(pad "240" smd rect
			(at -4.59994 85.849968 270)
			(size 1.8034 0.508)
			(layers "B.Cu" "B.Mask" "B.Paste")
			(net "M_L_DQ<37>")
		)
	)
)
